FILE_TYPE = CONNECTIVITY;
{Allegro Design Entry HDL 17.4-2019 S026 (4007227) 1/17/2022}
"PAGE_NUMBER" = 9;
0"NC";
END.
